(kicad_pcb
	(version 20260206)
	(generator "pcbnew")
	(generator_version "10.0")
	(general
		(thickness 1.6)
		(legacy_teardrops no)
	)
	(paper "A4")
	(title_block
		(title "fcb — 12433-1M.1206WZS1330.brd")
		(comment 1 "Open Vault / Knox (Wiwynn) / footprints 257-260 of 495")
	)
	(layers
		(0 "F.Cu" signal "TOP")
		(4 "In1.Cu" signal "L2GND")
		(6 "In2.Cu" signal "L3VCC")
		(2 "B.Cu" signal "BOTTOM")
		(9 "F.Adhes" user "F.Adhesive")
		(11 "B.Adhes" user "B.Adhesive")
		(13 "F.Paste" user "Package Geometry/Pastemask Top")
		(15 "B.Paste" user "Package Geometry/Pastemask Bottom")
		(5 "F.SilkS" user "Ref Des/Silkscreen Top")
		(7 "B.SilkS" user "Ref Des/Silkscreen Bottom")
		(1 "F.Mask" user "Board Geometry/Soldermask Top")
		(3 "B.Mask" user "Board Geometry/Soldermask Bottom")
		(17 "Dwgs.User" user "User.Drawings")
		(19 "Cmts.User" user "User.Comments")
		(21 "Eco1.User" user "User.Eco1")
		(23 "Eco2.User" user "User.Eco2")
		(25 "Edge.Cuts" user "Board Geometry/Outline")
		(27 "Margin" user)
		(31 "F.CrtYd" user "Package Geometry/Place Bound Top")
		(29 "B.CrtYd" user "Package Geometry/Place Bound Bottom")
		(35 "F.Fab" user "Ref Des/Assembly Top")
		(33 "B.Fab" user "Ref Des/Assembly Bottom")
	)
	(footprint ""
		(layer "F.Cu")
		(at 28.321 -352.425 -90)
		(property "Reference" "C260"
			(at 0 0 270)
			(layer "F.SilkS")
			(hide yes)
			(effects
				(font
					(size 1.27 1.27)
				)
			)
		)
		(property "Value" "SC10U25V6KX-1GP"
			(at -0.0762 -5.1308 270)
			(unlocked yes)
			(layer "F.Fab")
			(hide yes)
			(effects
				(font
					(size 1.016 1.016)
					(thickness 0.1524)
				)
			)
		)
		(property "Device Type" "C1206H71"
			(at -0.127 -6.6548 270)
			(unlocked yes)
			(layer "F.Fab")
			(hide yes)
			(effects
				(font
					(size 1.016 1.016)
					(thickness 0.1524)
				)
			)
		)
		(duplicate_pad_numbers_are_jumpers no)
		(fp_line
			(start -1.016 2.2352)
			(end -1.016 0.8382)
			(stroke
				(width 0.1524)
				(type default)
			)
			(layer "F.SilkS")
		)
		(fp_line
			(start 1.016 2.2352)
			(end -1.016 2.2352)
			(stroke
				(width 0.1524)
				(type default)
			)
			(layer "F.SilkS")
		)
		(fp_line
			(start 1.016 0.8382)
			(end 1.016 2.2352)
			(stroke
				(width 0.1524)
				(type default)
			)
			(layer "F.SilkS")
		)
		(fp_line
			(start -1.016 -0.8382)
			(end -1.016 -2.2352)
			(stroke
				(width 0.1524)
				(type default)
			)
			(layer "F.SilkS")
		)
		(fp_line
			(start -1.016 -2.2352)
			(end 1.016 -2.2352)
			(stroke
				(width 0.1524)
				(type default)
			)
			(layer "F.SilkS")
		)
		(fp_line
			(start 1.016 -2.2352)
			(end 1.016 -0.8382)
			(stroke
				(width 0.1524)
				(type default)
			)
			(layer "F.SilkS")
		)
		(fp_rect
			(start -1.0922 2.3114)
			(end 1.0922 -2.3114)
			(stroke
				(width 0)
				(type default)
			)
			(fill no)
			(layer "F.CrtYd")
		)
		(fp_poly
			(pts
				(xy 1.0922 -2.3114) (xy 1.0922 2.3114) (xy -1.0922 2.3114) (xy -1.0922 -2.3114)
			)
			(stroke
				(width 0)
				(type default)
			)
			(fill no)
			(layer "F.Fab")
		)
		(pad "1" smd rect
			(at 0 -1.397 270)
			(size 1.651 1.27)
			(layers "F.Cu" "F.Mask" "F.Paste")
			(net "OTP_RETRY_G")
		)
		(pad "2" smd rect
			(at 0 1.397 270)
			(size 1.651 1.27)
			(layers "F.Cu" "F.Mask" "F.Paste")
			(net "GND")
		)
	)
	(footprint ""
		(layer "F.Cu")
		(at 29.718 -368.808 90)
		(property "Reference" "PU1"
			(at 0 0 90)
			(layer "F.SilkS")
			(hide yes)
			(effects
				(font
					(size 1.27 1.27)
				)
			)
		)
		(property "Value" "ADM1276-3ACPZ-RL-GP"
			(at -5.3975 -5.0292 90)
			(unlocked yes)
			(layer "F.Fab")
			(hide yes)
			(effects
				(font
					(size 1.016 1.016)
					(thickness 0.1524)
				)
			)
		)
		(property "Device Type" "QFN20-G3D25H32"
			(at -5.3975 -6.5532 90)
			(unlocked yes)
			(layer "F.Fab")
			(hide yes)
			(effects
				(font
					(size 1.016 1.016)
					(thickness 0.1524)
				)
			)
		)
		(duplicate_pad_numbers_are_jumpers no)
		(fp_line
			(start -3.5179 -3.5179)
			(end -2.2479 -3.5179)
			(stroke
				(width 0.1524)
				(type default)
			)
			(layer "F.SilkS")
		)
		(fp_line
			(start -1.3208 -3.302)
			(end -1.3208 -3.81)
			(stroke
				(width 0.1524)
				(type default)
			)
			(layer "F.SilkS")
		)
		(fp_line
			(start -3.5179 -2.2479)
			(end -3.5179 -3.5179)
			(stroke
				(width 0.1524)
				(type default)
			)
			(layer "F.SilkS")
		)
		(fp_line
			(start 3.302 -1.2954)
			(end 4.064 -1.2954)
			(stroke
				(width 0.1524)
				(type default)
			)
			(layer "F.SilkS")
		)
		(fp_line
			(start -4.064 1.2954)
			(end -3.302 1.2954)
			(stroke
				(width 0.1524)
				(type default)
			)
			(layer "F.SilkS")
		)
		(fp_line
			(start -3.5179 2.2479)
			(end -3.5179 3.5179)
			(stroke
				(width 0.1524)
				(type default)
			)
			(layer "F.SilkS")
		)
		(fp_line
			(start 3.5179 3.5179)
			(end 3.5179 2.2479)
			(stroke
				(width 0.1524)
				(type default)
			)
			(layer "F.SilkS")
		)
		(fp_line
			(start 2.2479 3.5179)
			(end 3.5179 3.5179)
			(stroke
				(width 0.1524)
				(type default)
			)
			(layer "F.SilkS")
		)
		(fp_line
			(start -3.5179 3.5179)
			(end -2.2479 3.5179)
			(stroke
				(width 0.1524)
				(type default)
			)
			(layer "F.SilkS")
		)
		(fp_line
			(start 1.2954 3.81)
			(end 1.2954 3.302)
			(stroke
				(width 0.1524)
				(type default)
			)
			(layer "F.SilkS")
		)
		(fp_poly
			(pts
				(xy 2.2479 -3.5179) (xy 3.5179 -2.2479) (xy 3.5179 -3.5179)
			)
			(stroke
				(width 0)
				(type default)
			)
			(fill yes)
			(layer "F.SilkS")
		)
		(fp_rect
			(start -2.5019 2.5019)
			(end 2.5019 -2.5019)
			(stroke
				(width 0)
				(type default)
			)
			(fill no)
			(layer "F.CrtYd")
		)
		(fp_poly
			(pts
				(xy -3.5179 3.5179) (xy -3.5179 -2.49682) (xy -2.5019 -2.49682) (xy -2.5019 2.5019) (xy 2.5019 2.5019)
				(xy 2.5019 -2.5019) (xy -3.5179 -2.5019) (xy -3.5179 -3.5179) (xy 3.5179 -3.5179) (xy 3.5179 3.5179)
			)
			(stroke
				(width 0)
				(type default)
			)
			(fill no)
			(layer "F.CrtYd")
		)
		(fp_rect
			(start -3.5179 3.5179)
			(end 3.5179 -3.5179)
			(stroke
				(width 0)
				(type default)
			)
			(fill no)
			(layer "F.Fab")
		)
		(pad "1" smd rect
			(at 1.299972 -2.4384 90)
			(size 0.4064 1.143)
			(layers "F.Cu" "F.Mask" "F.Paste")
			(net "ADM1276_OV")
		)
		(pad "2" smd rect
			(at 0.649986 -2.4384 90)
			(size 0.4064 1.143)
			(layers "F.Cu" "F.Mask" "F.Paste")
			(net "ADM1276_VCAP")
		)
		(pad "3" smd rect
			(at 0 -2.4384 90)
			(size 0.4064 1.143)
			(layers "F.Cu" "F.Mask" "F.Paste")
			(net "ADM1276_ISET")
		)
		(pad "4" smd rect
			(at -0.649986 -2.4384 90)
			(size 0.4064 1.143)
			(layers "F.Cu" "F.Mask" "F.Paste")
			(net "ADM1276_SS")
		)
		(pad "5" smd rect
			(at -1.299972 -2.4384 90)
			(size 0.4064 1.143)
			(layers "F.Cu" "F.Mask" "F.Paste")
			(net "ADM1276_TIMER")
		)
		(pad "6" smd rect
			(at -2.4384 -1.299972 90)
			(size 1.143 0.4064)
			(layers "F.Cu" "F.Mask" "F.Paste")
			(net "ADM1276_LATCH#")
		)
		(pad "7" smd rect
			(at -2.4384 -0.649986 90)
			(size 1.143 0.4064)
			(layers "F.Cu" "F.Mask" "F.Paste")
			(net "ADM1276_ADR")
		)
		(pad "8" smd rect
			(at -2.4384 0 90)
			(size 1.143 0.4064)
			(layers "F.Cu" "F.Mask" "F.Paste")
			(net "ADM1276_EN")
		)
		(pad "9" smd rect
			(at -2.4384 0.649986 90)
			(size 1.143 0.4064)
			(layers "F.Cu" "F.Mask" "F.Paste")
			(net "ADM1276_GPIO2")
		)
		(pad "10" smd rect
			(at -2.4384 1.299972 90)
			(size 1.143 0.4064)
			(layers "F.Cu" "F.Mask" "F.Paste")
			(net "I2C_C_SDA_ADM1276")
		)
		(pad "11" smd rect
			(at -1.299972 2.4384 90)
			(size 0.4064 1.143)
			(layers "F.Cu" "F.Mask" "F.Paste")
			(net "I2C_C_SCL_ADM1276")
		)
		(pad "12" smd rect
			(at -0.649986 2.4384 90)
			(size 0.4064 1.143)
			(layers "F.Cu" "F.Mask" "F.Paste")
			(net "ADM1276_PWRGD")
		)
		(pad "13" smd rect
			(at 0 2.4384 90)
			(size 0.4064 1.143)
			(layers "F.Cu" "F.Mask" "F.Paste")
			(net "ADM1276_FLB")
		)
		(pad "14" smd rect
			(at 0.649986 2.4384 90)
			(size 0.4064 1.143)
			(layers "F.Cu" "F.Mask" "F.Paste")
			(net "ADM1276_VOUT")
		)
		(pad "15" smd rect
			(at 1.299972 2.4384 90)
			(size 0.4064 1.143)
			(layers "F.Cu" "F.Mask" "F.Paste")
			(net "GND")
		)
		(pad "16" smd rect
			(at 2.4384 1.299972 90)
			(size 1.143 0.4064)
			(layers "F.Cu" "F.Mask" "F.Paste")
			(net "ADM1276_GATE_DRV")
		)
		(pad "17" smd rect
			(at 2.4384 0.649986 90)
			(size 1.143 0.4064)
			(layers "F.Cu" "F.Mask" "F.Paste")
			(net "ADM1276_SENSE-")
		)
		(pad "18" smd rect
			(at 2.4384 0 90)
			(size 1.143 0.4064)
			(layers "F.Cu" "F.Mask" "F.Paste")
			(net "ADM1276_SENSE+")
		)
		(pad "19" smd rect
			(at 2.4384 -0.649986 90)
			(size 1.143 0.4064)
			(layers "F.Cu" "F.Mask" "F.Paste")
			(net "ADM1276_VCC")
		)
		(pad "20" smd rect
			(at 2.4384 -1.299972 90)
			(size 1.143 0.4064)
			(layers "F.Cu" "F.Mask" "F.Paste")
			(net "ADM1276_UV")
		)
		(pad "21" smd rect
			(at 0 0 90)
			(size 3.2512 3.2512)
			(layers "F.Cu" "F.Mask" "F.Paste")
			(net "GND")
		)
	)
	(footprint ""
		(layer "F.Cu")
		(at 16.052292 -289.636962 180)
		(property "Reference" "R102"
			(at 0 0 180)
			(layer "F.SilkS")
			(hide yes)
			(effects
				(font
					(size 1.27 1.27)
				)
			)
		)
		(property "Value" "10KR2F-2-GP"
			(at 0.064008 -3.993896 180)
			(unlocked yes)
			(layer "F.Fab")
			(hide yes)
			(effects
				(font
					(size 1.016 1.016)
					(thickness 0.1524)
				)
			)
		)
		(property "Device Type" "R402H16"
			(at 0.064008 -5.517896 180)
			(unlocked yes)
			(layer "F.Fab")
			(hide yes)
			(effects
				(font
					(size 1.016 1.016)
					(thickness 0.1524)
				)
			)
		)
		(duplicate_pad_numbers_are_jumpers no)
		(fp_line
			(start 0.508 -0.9398)
			(end -0.508 -0.9398)
			(stroke
				(width 0.1524)
				(type default)
			)
			(layer "F.SilkS")
		)
		(fp_line
			(start -0.508 -0.9398)
			(end -0.508 0.9398)
			(stroke
				(width 0.1524)
				(type default)
			)
			(layer "F.SilkS")
		)
		(fp_rect
			(start -0.508 0.9398)
			(end 0.508 -0.9398)
			(stroke
				(width 0)
				(type default)
			)
			(fill no)
			(layer "F.CrtYd")
		)
		(fp_rect
			(start -0.508 0.9398)
			(end 0.508 -0.9398)
			(stroke
				(width 0)
				(type default)
			)
			(fill no)
			(layer "F.Fab")
		)
		(pad "1" smd custom
			(at 0 -0.4445 180)
			(size 0.1397 0.1397)
			(layers "F.Cu" "F.Mask" "F.Paste")
			(net "FANIN_3")
			(options
				(clearance outline)
				(anchor circle)
			)
			(primitives
				(gr_poly
					(pts
						(arc
							(start -0.1778 -0.2794)
							(mid -0.249642 -0.249642)
							(end -0.2794 -0.1778)
						)
						(arc
							(start -0.2794 0.1778)
							(mid -0.249642 0.249642)
							(end -0.1778 0.2794)
						)
						(arc
							(start 0.1778 0.2794)
							(mid 0.249642 0.249642)
							(end 0.2794 0.1778)
						)
						(arc
							(start 0.2794 -0.1778)
							(mid 0.249642 -0.249642)
							(end 0.1778 -0.2794)
						)
					)
					(width 0)
					(fill yes)
				)
			)
		)
		(pad "2" smd custom
			(at 0 0.4445 180)
			(size 0.1397 0.1397)
			(layers "F.Cu" "F.Mask" "F.Paste")
			(net "GND")
			(options
				(clearance outline)
				(anchor circle)
			)
			(primitives
				(gr_poly
					(pts
						(arc
							(start -0.1778 -0.2794)
							(mid -0.249642 -0.249642)
							(end -0.2794 -0.1778)
						)
						(arc
							(start -0.2794 0.1778)
							(mid -0.249642 0.249642)
							(end -0.1778 0.2794)
						)
						(arc
							(start 0.1778 0.2794)
							(mid 0.249642 0.249642)
							(end 0.2794 0.1778)
						)
						(arc
							(start 0.2794 -0.1778)
							(mid 0.249642 -0.249642)
							(end 0.1778 -0.2794)
						)
					)
					(width 0)
					(fill yes)
				)
			)
		)
	)
	(footprint ""
		(layer "F.Cu")
		(at 21.336 -375.285 -90)
		(property "Reference" "PC10"
			(at 0 0 270)
			(layer "F.SilkS")
			(hide yes)
			(effects
				(font
					(size 1.27 1.27)
				)
			)
		)
		(property "Value" "SC1U25V5KX-1GP"
			(at -0.0762 -6.1214 270)
			(unlocked yes)
			(layer "F.Fab")
			(hide yes)
			(effects
				(font
					(size 1.016 1.016)
					(thickness 0.1524)
				)
			)
		)
		(property "Device Type" "C805H58"
			(at -0.0762 -8.1534 270)
			(unlocked yes)
			(layer "F.Fab")
			(hide yes)
			(effects
				(font
					(size 1.016 1.016)
					(thickness 0.1524)
				)
			)
		)
		(duplicate_pad_numbers_are_jumpers no)
		(fp_line
			(start 0.635 0)
			(end -0.635 0)
			(stroke
				(width 0.508)
				(type default)
			)
			(layer "F.SilkS")
		)
		(fp_rect
			(start -0.9652 1.778)
			(end 0.9652 -1.778)
			(stroke
				(width 0)
				(type default)
			)
			(fill no)
			(layer "F.CrtYd")
		)
		(fp_poly
			(pts
				(xy -0.9652 -1.778) (xy 0.9652 -1.778) (xy 0.9652 1.778) (xy -0.9652 1.778)
			)
			(stroke
				(width 0)
				(type default)
			)
			(fill no)
			(layer "F.Fab")
		)
		(pad "1" smd rect
			(at 0 -0.9652 270)
			(size 1.397 1.143)
			(layers "F.Cu" "F.Mask" "F.Paste")
			(net "ADM1276_UV")
		)
		(pad "2" smd rect
			(at 0 0.9652 270)
			(size 1.397 1.143)
			(layers "F.Cu" "F.Mask" "F.Paste")
			(net "GND")
		)
	)
)
